FILE_TYPE = CONNECTIVITY;
{Allegro Design Entry HDL 16.6-p007 (v16-6-112F) 10/10/2012}
"PAGE_NUMBER" = 118;
0"NC";
1"P1V05_PCH_STBY_KR_PLL\g";
2"P1V05_PCH_STBY_KR_PLL\g";
3"P3V3_STBY\g";
4"P3V3_STBY\g";
5"GND\g";
6"P3V3_STBY\g";
7"GND\g";
8"P3V3_STBY\g";
9"GND\g";
10"GND\g";
11"IRQ_LVC3_WAKE_N";
12"FM_SLP_SUS_N";
13"PWRGD_SYS_PWROK";
14"PWRGD_CPUPWRGD_GTL";
15"PWRGD_DSW_PWROK";
16"PWRGD_PCH_PWROK";
17"H_PM_SYNC_GTL";
18"FM_1GB_LOM_DISABLE_N";
19"FM_10GBE_LOM_DISABLE_N";
20"FM_GBE_LOM_DISABLE_N";
21"A_KR1_RBIAS";
22"H_PM_SYNC1_GTL_R";
23"TP_SLP_LAN_N";
24"RST_RSMRST_N";
25"RST_BMC_SYSRST_BTN_OUT_B_N";
26"FM_PCH_LVC1_THERMTRIP_N";
27"PECI_PCH";
28"XTAL_KR_25M_OUT";
29"TP_PLTRST_CPU_N";
30"TP_PM_SYNC_GTL";
31"TP_PCH_RSVD54";
32"TP_PCH_RSVD53";
33"KR_P3_OCP_TX_DP";
34"KR_P3_OCP_TX_DN";
35"KR_P2_OCP_TX_DP";
36"KR_P2_OCP_TX_DN";
37"KR_P1_OCP_TX_DP";
38"KR_P1_OCP_TX_DN";
39"KR_P0_OCP_TX_DP";
40"KR_P0_OCP_TX_DN";
41"TP_10GBE_KR1_MON_DP";
42"TP_10GBE_KR1_MON_DN";
43"TP_PCH_RSVD42";
44"TP_PCH_RSVD41";
45"XDP_CPU_PWR_DEBUG_N";
46"FM_GBE_LOM_DISABLE_N";
47"FM_CPU0_RC_ERROR_N";
48"FM_BMC_CPLD_MP_RST_N";
49"IRQ_SML1_PMBUS_ALERT_N";
50"FM_BATTERY_SENSE_EN_N";
51"FM_CPU0_SKTOCC_LVT3_N";
52"FM_SLPS4_N";
53"FM_SLPS3_N";
54"FM_PCH_PWRBTN_N";
55"FM_CPU1_SKTOCC_LVT3_N";
56"XDP_PCH_PWR_DEBUG_N";
57"TP_PCH_RSVD32";
58"TP_PCH_RSVD33";
59"TP_PCH_RSVD45";
60"TP_PCH_RSVD36";
61"TP_PCH_RSVD35";
62"TP_PCH_RSVD34";
63"TP_CPU_PCH_TRIGGER_IN";
64"TP_CPU_PCH_TRIGGER_OUT";
65"KR_P3_OCP_RX_C_DP";
66"KR_P3_OCP_RX_C_DN";
67"KR_P2_OCP_RX_C_DP";
68"KR_P2_OCP_RX_C_DN";
69"KR_P1_OCP_RX_C_DP";
70"KR_P1_OCP_RX_C_DN";
71"KR_P0_OCP_RX_C_DP";
72"KR_P0_OCP_RX_C_DN";
73"XDP_PCH_TCK1";
74"XDP_TDI";
75"XDP_TDO";
76"XDP_TMS";
77"XDP_PCH_CPU_TCK0";
78"XDP_PRDY_N";
79"XDP_ITP_PMODE";
80"XDP_TRST_N";
81"XDP_PREQ_N";
82"XDP_PCH_PWR_DEBUG_N";
83"TP_10GBE_KR0_MON_DP";
84"TP_10GBE_KR0_MON_DN";
85"TP_PCH_RSVD38";
86"TP_PCH_RSVD37";
87"PWRGD_PVCCIO_CPU0";
88"XTAL_KR_25M_IN";
89"RST_BMC_SRST_R_N";
90"A_KR0_RBIAS";
91"RST_BMC_SRST_N";
92"XTAL_KR_25M_OUT";
93"XTAL_KR_25M_IN";
%"P1V05_PCH_STBY_KR_PLL"
"1","(-1000,2025)","0","mstr_symbols","I117";
;
BOM_COST"SB"
ROOM"SB_DECOUPLING"
HDL_POWER"P1V05_PCH_STBY_KR_PLL"
CDS_LIB"mstr_symbols"
VOLTAGE"1.05V"
BODY_TYPE"PLUMBING";
"G\NAC"1;
%"P1V05_PCH_STBY_KR_PLL"
"1","(-7225,2400)","0","mstr_symbols","I118";
;
BOM_COST"SB"
VOLTAGE"1.05V"
CDS_LIB"mstr_symbols"
BODY_TYPE"PLUMBING"
ROOM"SB_DECOUPLING"
HDL_POWER"P1V05_PCH_STBY_KR_PLL";
"G\NAC"2;
%"RES"
"1","(-1675,900)","0","mstr_discrete","I120";
;
CDS_SEC"1"
SEC"1"
SEC_TYPE"0402"
BOM_COST"SB"
ROOM"SB"
CDS_LOCATION"R8C24"
CDS_LIB"mstr_discrete"
PART_NUMBER"G21497-005"
PACK_TYPE"0402"
LOCATION"R8C24"
TOLERANCE"5%"
MATERIAL"CHIP"
VALUE"0.0"
WATTAGE"1/16W";
"B"
$PN"2"18;
"A"
$PN"1"20;
%"RES"
"1","(-1675,675)","0","mstr_discrete","I125";
;
CDS_SEC"1"
ROOM"SB"
BOM_COST"SB"
SEC_TYPE"0402"
SEC"1"
CDS_LOCATION"R8C23"
CDS_LIB"mstr_discrete"
MATERIAL"EMPTY"
PART_NUMBER"G21497-005"
PACK_TYPE"0402"
LOCATION"R8C23"
TOLERANCE"5%"
VALUE"0.0"
WATTAGE"1/16W";
"B"
$PN"2"19;
"A"
$PN"1"20;
%"RES"
"2","(-2200,1100)","0","mstr_discrete","I128";
;
CDS_SEC"1"
SEC"1"
SEC_TYPE"0402"
CDS_LOCATION"R2N6"
CDS_LIB"mstr_discrete"
ROOM"SB"
BOM_COST"SB"
LOCATION"R2N6"
PART_NUMBER"G21796-016"
VALUE"10.0K"
PACK_TYPE"0402"
MATERIAL"CHIP"
WATTAGE"1/16W"
TOLERANCE"1%";
"A"
$PN"1"3;
"B"
$PN"2"20;
%"P3V3_STBY"
"1","(-2200,1275)","0","mstr_symbols","I129";
;
SIZE"1B"
CDS_LIB"mstr_symbols"
BODY_TYPE"PLUMBING"
VOLTAGE"3.3V"
HDL_POWER"P3V3_STBY";
"G\NAC"3;
%"RES"
"1","(-6750,3975)","0","mstr_discrete","I131";
;
CDS_SEC"1"
SEC"1"
SEC_TYPE"0402"
BOM_COST"SB"
ROOM"SB"
CDS_LIB"mstr_discrete"
CDS_LOCATION"R7D23"
PACK_TYPE"0402"
PART_NUMBER"G21497-005"
LOCATION"R7D23"
TOLERANCE"5%"
MATERIAL"CHIP"
VALUE"0.0"
WATTAGE"1/16W";
"B"
$PN"2"89;
"A"
$PN"1"91;
%"P3V3_STBY"
"1","(-5200,625)","0","mstr_symbols","I135";
;
SIZE"1B"
CDS_LIB"mstr_symbols"
BODY_TYPE"PLUMBING"
VOLTAGE"3.3V"
HDL_POWER"P3V3_STBY";
"G\NAC"4;
%"CAP_A"
"1","(-5200,375)","0","dev_discrete","I136";
;
ROOM"SB"
BOM_COST"SB"
CDS_SEC"1"
SEC"1"
SEC_TYPE"0402V"
CDS_LOCATION"C7D1"
CDS_LIB"dev_discrete"
LOCATION"C7D1"
PART_NUMBER"A36096-030"
VALUE"0.1UF"
TOLERANCE"10%"
PACK_TYPE"0402V"
VOLTAGE"16V"
MATERIAL"X7R";
"B"
$PN"2"5;
"A"
$PN"1"4;
%"GND"
"1","(-5200,125)","0","mstr_symbols","I137";
;
HDL_POWER"GND"
VOLTAGE"0.0V"
CDS_LIB"mstr_symbols"
SIZE"1B"
BODY_TYPE"PLUMBING";
"A\NAC"5;
%"74CBTLV1G125"
"1","(-4575,1075)","0","mstr_ttl","I142";
;
$SEC"1"
CDS_SEC"1"
CDS_LIB"mstr_ttl"
CDS_LOCATION"U7D1"
BOM_COST"DEBUG"
ROOM"DEBUG"
POWER_GROUP"VCC=P3V3_STBY;GND=GND;"
LOCATION"U7D1"
MATERIAL"IC"
PART_NUMBER"C88177-001"
PACK_TYPE"SMLF";
"OE_N \B"
$PN"1"87;
"B"
$PN"4"45;
"A"
$PN"2"82;
%"RES"
"2","(-5175,1275)","0","mstr_discrete","I144";
;
CDS_SEC"1"
SEC_TYPE"0402"
SEC"1"
CDS_LOCATION"R7C23"
CDS_LIB"mstr_discrete"
ROOM"SB"
BOM_COST"SB"
WATTAGE"1/16W"
LOCATION"R7C23"
PART_NUMBER"G21796-016"
VALUE"10.0K"
TOLERANCE"1%"
PACK_TYPE"0402"
MATERIAL"CHIP";
"A"
$PN"1"6;
"B"
$PN"2"82;
%"P3V3_STBY"
"1","(-5175,1450)","0","mstr_symbols","I145";
;
CDS_LIB"mstr_symbols"
SIZE"1B"
VOLTAGE"3.3V"
BODY_TYPE"PLUMBING"
HDL_POWER"P3V3_STBY";
"G\NAC"6;
%"RES"
"1","(-1575,2675)","0","mstr_discrete","I66";
;
CDS_SEC"1"
SEC_TYPE"0402"
BOM_COST"SB"
SEC"1"
ROOM"SB"
CDS_LIB"mstr_discrete"
CDS_LOCATION"R3N9"
PACK_TYPE"0402"
LOCATION"R3N9"
PART_NUMBER"G21796-066"
TOLERANCE"1%"
MATERIAL"CHIP"
WATTAGE"1/16W"
VALUE"10.0";
"B"
$PN"2"17;
"A"
$PN"1"22;
%"RES"
"2","(-1075,2475)","0","mstr_discrete","I67";
;
CDS_SEC"1"
SEC"1"
BOM_COST"SB"
SEC_TYPE"0402"
ROOM"SB"
CDS_LOCATION"R3N14"
CDS_LIB"mstr_discrete"
MATERIAL"EMPTY"
LOCATION"R3N14"
PART_NUMBER"G21796-047"
VALUE"49.9"
TOLERANCE"1%"
PACK_TYPE"0402"
WATTAGE"1/16W";
"A"
$PN"1"17;
"B"
$PN"2"7;
%"GND"
"1","(-1075,2225)","0","mstr_symbols","I69";
;
SIZE"1B"
HDL_POWER"GND"
VOLTAGE"0.0V"
CDS_LIB"mstr_symbols"
BODY_TYPE"PLUMBING";
"A\NAC"7;
%"RES"
"2","(-2300,4650)","0","mstr_discrete","I71";
;
CDS_SEC"1"
SEC_TYPE"0402"
BOM_COST"SB"
SEC"1"
ROOM"SB"
CDS_LIB"mstr_discrete"
CDS_LOCATION"R3N13"
PART_NUMBER"G21796-072"
WATTAGE"1/16W"
VALUE"4.75K"
LOCATION"R3N13"
TOLERANCE"1%"
PACK_TYPE"0402"
MATERIAL"CHIP";
"A"
$PN"1"8;
"B"
$PN"2"11;
%"P3V3_STBY"
"1","(-2300,4875)","0","mstr_symbols","I72";
;
CDS_LIB"mstr_symbols"
SIZE"1B"
VOLTAGE"3.3V"
BODY_TYPE"PLUMBING"
HDL_POWER"P3V3_STBY";
"G\NAC"8;
%"LBG_CORE_QAT_EXT_D"
"5","(-4025,3025)","0","mstr_u_proc","I73";
;
CDS_SEC"5"
CDS_LIB"mstr_u_proc"
BOM_COST"SB"
ROOM"SB"
PACK_TYPE"BGA1"
SEC_TYPE"BGA1"
SEC"5"
CDS_LOCATION"U7C1"
LOCATION"U7C1"
MATERIAL"IC"
PART_NUMBER"H91415-002";
"WAKE_N"
$PN"K9"11;
"TRIGGER_OUT"
$PN"R13"64;
"TRIGGER_IN"
$PN"M7"63;
"THRMTRIP_N"
$PN"V15"26;
"SYS_RESET_N"
$PN"BV19"25;
"SYS_PWROK"
$PN"BY19"13;
"SLP_SUS_N"
$PN"P7"12;
"SLP_GBE_N"
$PN"M15"23;
"RSVD<32>"
$PN"AA54"57;
"RSVD<33>"
$PN"V56"58;
"RSVD<34>"
$PN"Y56"62;
"RSVD<35>"
$PN"W54"61;
"RSVD<36>"
$PN"AK54"60;
"RSVD<37>"
$PN"BN29"86;
"RSVD<38>"
$PN"BL29"85;
"RSVD<39>"
$PN"BL26"84;
"RSVD<40>"
$PN"BN26"83;
"RSVD<41>"
$PN"BJ40"44;
"RSVD<42>"
$PN"BG40"43;
"RSVD<43>"
$PN"BL33"42;
"RSVD<44>"
$PN"BN33"41;
"RSVD<45>"
$PN"P22"59;
"RSVD<53>"
$PN"P26"32;
"RSVD<54>"
$PN"R24"31;
"RSMRST_N"
$PN"P15"24;
"PROC_PWRGD"
$PN"R9"14;
"PREQ_N"
$PN"U54"81;
"PRDY_N"
$PN"AD54"78;
"PM_SYNC2"
$PN"V7"30;
"PM_SYNC"
$PN"U13"22;
"PLTRST_CPU_N"
$PN"U17"29;
"PECI"
$PN"U9"27;
"PCH_PWROK"
$PN"R17"16;
"LAN_XTAL_OUT"
$PN"BY16"28;
"LAN_XTAL_IN"
$PN"BV16"88;
"LAN_TX_P3P"
$PN"BM31"33;
"LAN_TX_P3N"
$PN"BR31"34;
"LAN_TX_P2P"
$PN"BR35"35;
"LAN_TX_P2N"
$PN"BM35"36;
"LAN_TX_P1P"
$PN"BR24"37;
"LAN_TX_P1N"
$PN"BM24"38;
"LAN_TX_P0P"
$PN"BR27"39;
"LAN_TX_P0N"
$PN"BM27"40;
"LAN_RX_P3P"
$PN"BH35"65;
"LAN_RX_P3N"
$PN"BF35"66;
"LAN_RX_P2P"
$PN"BG37"67;
"LAN_RX_P2N"
$PN"BJ37"68;
"LAN_RX_P1P"
$PN"BJ29"69;
"LAN_RX_P1N"
$PN"BG29"70;
"LAN_RX_P0P"
$PN"BF31"71;
"LAN_RX_P0N"
$PN"BH31"72;
"LAN_RBIAS_1"
$PN"BD42"21;
"LAN_RBIAS_0"
$PN"BB29"90;
"JTAG_TMS"
$PN"AH54"76;
"JTAG_TDO"
$PN"AP56"75;
"JTAG_TDI"
$PN"AN54"74;
"JTAG_TCK"
$PN"AL56"73;
"JTAGX"
$PN"AF54"77;
"ITP_PMODE"
$PN"AR54"79;
"GPD9"
$PN"A15"48;
"GPD8_SUSCLK"
$PN"C13"49;
"GPD7"
$PN"H9"50;
"GPD6_SLP_A_N"
$PN"G11"51;
"GPD5_SLP_S4_N"
$PN"B16"52;
"GPD4_SLP_S3_N"
$PN"D14"53;
"GPD3_PWRBTN_N"
$PN"C15"54;
"GPD2_GBE_WAKE_N"
$PN"M11"89;
"GPD1_ACPRESENT"
$PN"H13"55;
"GPD11_GBEPHY"
$PN"A13"46;
"GPD10_SLP_S5_N"
$PN"B14"47;
"GPD0"
$PN"G15"56;
"DSW_PWROK"
$PN"K13"15;
"CPU_TRST_N"
$PN"AT56"80;
%"CRYSTAL"
"1","(-7400,850)","0","mstr_discrete","I76";
;
CDS_SEC"1"
BOM_COST"SB"
SEC"1"
SEC_TYPE"2013"
ROOM"SB"
CDS_LIB"mstr_discrete"
CDS_LOCATION"Y8C1"
PACK_TYPE"2013"
PART_NUMBER"H19611-001"
MATERIAL"IC"
LOCATION"Y8C1"
VALUE"25.000MHZ";
"B"
$PN"3"92;
"A"
$PN"1"93;
%"CAP"
"1","(-7250,600)","0","mstr_discrete","I77";
;
CDS_SEC"1"
BOM_COST"SB"
SEC"1"
SEC_TYPE"0402LF"
ROOM"SB"
CDS_LIB"mstr_discrete"
CDS_LOCATION"C8C2"
LOCATION"C8C2"
PART_NUMBER"A36095-031"
VALUE"33.0PF"
TOLERANCE"5%"
PACK_TYPE"0402LF"
VOLTAGE"50V"
MATERIAL"COG";
"A"
$PN"1"92;
"B"
$PN"2"9;
%"GND"
"1","(-7250,400)","0","mstr_symbols","I78";
;
HDL_POWER"GND"
CDS_LIB"mstr_symbols"
SIZE"1B"
BODY_TYPE"PLUMBING"
VOLTAGE"0.0V";
"A\NAC"9;
%"CAP"
"1","(-7700,625)","0","mstr_discrete","I79";
;
CDS_SEC"1"
ROOM"SB"
SEC_TYPE"0402LF"
BOM_COST"SB"
SEC"1"
CDS_LOCATION"C8C1"
CDS_LIB"mstr_discrete"
MATERIAL"COG"
VOLTAGE"50V"
TOLERANCE"5%"
VALUE"33.0PF"
LOCATION"C8C1"
PART_NUMBER"A36095-031"
PACK_TYPE"0402LF";
"A"
$PN"1"93;
"B"
$PN"2"10;
%"GND"
"1","(-7700,425)","0","mstr_symbols","I80";
;
SIZE"1B"
HDL_POWER"GND"
BODY_TYPE"PLUMBING"
CDS_LIB"mstr_symbols"
VOLTAGE"0.0V";
"A\NAC"10;
%"RES"
"2","(-7225,2175)","0","mstr_discrete","I96";
;
CDS_SEC"1"
SEC"1"
SEC_TYPE"0402"
ROOM"SB"
CDS_LOCATION"R2N4"
CDS_LIB"mstr_discrete"
LOCATION"R2N4"
PART_NUMBER"G85996-004"
VALUE"1.0K"
TOLERANCE"0.1%"
MATERIAL"CHIP"
WATTAGE"1/16W"
PACK_TYPE"0402";
"A"
$PN"1"2;
"B"
$PN"2"90;
%"RES"
"1","(-1700,1875)","0","mstr_discrete","I99";
;
CDS_SEC"1"
SEC"1"
SEC_TYPE"0402"
ROOM"SB"
CDS_LIB"mstr_discrete"
CDS_LOCATION"R2M6"
PART_NUMBER"G85996-004"
PACK_TYPE"0402"
LOCATION"R2M6"
TOLERANCE"0.1%"
MATERIAL"CHIP"
VALUE"1.0K"
WATTAGE"1/16W";
"B"
$PN"2"1;
"A"
$PN"1"21;
END.
